(kicad_pcb
	(version 20260206)
	(generator "pcbnew")
	(generator_version "10.0")
	(general
		(thickness 1.6)
		(legacy_teardrops no)
	)
	(paper "A4")
	(title_block
		(title "12092022_DA0F0TFB6D0_F0T_FAN_BOARD_MP5048_D_brd_v02_OCP.brd")
		(comment 1 "Grand Teton / footprints 218-221 of 924")
	)
	(layers
		(0 "F.Cu" signal "TOP")
		(4 "In1.Cu" signal "GND")
		(6 "In2.Cu" signal "IN1")
		(8 "In3.Cu" signal "IN2")
		(10 "In4.Cu" signal "GND1")
		(2 "B.Cu" signal "BOTTOM")
		(9 "F.Adhes" user "F.Adhesive")
		(11 "B.Adhes" user "B.Adhesive")
		(13 "F.Paste" user "Package Geometry/Pastemask Top")
		(15 "B.Paste" user "Package Geometry/Pastemask Bottom")
		(5 "F.SilkS" user "Ref Des/Silkscreen Top")
		(7 "B.SilkS" user "Ref Des/Silkscreen Bottom")
		(1 "F.Mask" user "Board Geometry/Soldermask Top")
		(3 "B.Mask" user "Board Geometry/Soldermask Bottom")
		(17 "Dwgs.User" user "User.Drawings")
		(19 "Cmts.User" user "User.Comments")
		(21 "Eco1.User" user "User.Eco1")
		(23 "Eco2.User" user "User.Eco2")
		(25 "Edge.Cuts" user "Board Geometry/Outline")
		(27 "Margin" user)
		(31 "F.CrtYd" user "Package Geometry/Place Bound Top")
		(29 "B.CrtYd" user "Package Geometry/Place Bound Bottom")
		(35 "F.Fab" user "Ref Des/Assembly Top")
		(33 "B.Fab" user "Ref Des/Assembly Bottom")
	)
	(footprint ""
		(layer "F.Cu")
		(at 43.942 -131.572)
		(property "Reference" "U403"
			(at 2.794 3.07467 0)
			(unlocked yes)
			(layer "F.SilkS")
			(effects
				(font
					(size 0.7874 0.5842)
					(thickness 0.1524)
				)
				(justify left)
			)
		)
		(property "Value" ""
			(at 0 0 0)
			(layer "F.Fab")
			(effects
				(font
					(size 1.27 1.27)
				)
			)
		)
		(duplicate_pad_numbers_are_jumpers no)
		(fp_line
			(start -2.6416 0.762)
			(end -3.1496 0.762)
			(stroke
				(width 0.1524)
				(type default)
			)
			(layer "F.SilkS")
		)
		(fp_line
			(start -1.999996 -1.999996)
			(end -1.524 -1.999996)
			(stroke
				(width 0.1524)
				(type default)
			)
			(layer "F.SilkS")
		)
		(fp_line
			(start -1.999996 -1.524)
			(end -1.999996 -1.999996)
			(stroke
				(width 0.1524)
				(type default)
			)
			(layer "F.SilkS")
		)
		(fp_line
			(start -1.999996 1.999996)
			(end -1.999996 1.524)
			(stroke
				(width 0.1524)
				(type default)
			)
			(layer "F.SilkS")
		)
		(fp_line
			(start -1.524 1.999996)
			(end -1.999996 1.999996)
			(stroke
				(width 0.1524)
				(type default)
			)
			(layer "F.SilkS")
		)
		(fp_line
			(start 0.254 2.6416)
			(end 0.254 3.6576)
			(stroke
				(width 0.1524)
				(type default)
			)
			(layer "F.SilkS")
		)
		(fp_line
			(start 0.762 -2.9464)
			(end 0.762 -2.6416)
			(stroke
				(width 0.1524)
				(type default)
			)
			(layer "F.SilkS")
		)
		(fp_line
			(start 1.524 -1.999996)
			(end 1.999996 -1.999996)
			(stroke
				(width 0.1524)
				(type default)
			)
			(layer "F.SilkS")
		)
		(fp_line
			(start 1.999996 -1.999996)
			(end 1.999996 -1.524)
			(stroke
				(width 0.1524)
				(type default)
			)
			(layer "F.SilkS")
		)
		(fp_line
			(start 1.999996 1.524)
			(end 1.999996 1.999996)
			(stroke
				(width 0.1524)
				(type default)
			)
			(layer "F.SilkS")
		)
		(fp_line
			(start 1.999996 1.999996)
			(end 1.524 1.999996)
			(stroke
				(width 0.1524)
				(type default)
			)
			(layer "F.SilkS")
		)
		(fp_line
			(start 3.1496 0.254)
			(end 2.6416 0.254)
			(stroke
				(width 0.1524)
				(type default)
			)
			(layer "F.SilkS")
		)
		(fp_poly
			(pts
				(xy -2.82067 -1.051814) (xy -3.59029 -0.667258) (xy -3.59029 -1.436624)
			)
			(stroke
				(width 0)
				(type default)
			)
			(fill yes)
			(layer "F.SilkS")
		)
		(fp_line
			(start -2.6416 0.762)
			(end -3.1496 0.762)
			(stroke
				(width 0.1)
				(type default)
			)
			(layer "F.Fab")
		)
		(fp_line
			(start -1.999996 -1.999996)
			(end 1.999996 -1.999996)
			(stroke
				(width 0.1)
				(type default)
			)
			(layer "F.Fab")
		)
		(fp_line
			(start -1.999996 1.999996)
			(end -1.999996 -1.999996)
			(stroke
				(width 0.1)
				(type default)
			)
			(layer "F.Fab")
		)
		(fp_line
			(start 0.254 2.6416)
			(end 0.254 3.6576)
			(stroke
				(width 0.1)
				(type default)
			)
			(layer "F.Fab")
		)
		(fp_line
			(start 0.762 -3.6576)
			(end 0.762 -2.6416)
			(stroke
				(width 0.1)
				(type default)
			)
			(layer "F.Fab")
		)
		(fp_line
			(start 1.999996 -1.999996)
			(end 1.999996 1.999996)
			(stroke
				(width 0.1)
				(type default)
			)
			(layer "F.Fab")
		)
		(fp_line
			(start 1.999996 1.999996)
			(end -1.999996 1.999996)
			(stroke
				(width 0.1)
				(type default)
			)
			(layer "F.Fab")
		)
		(fp_line
			(start 3.1496 0.254)
			(end 2.6416 0.254)
			(stroke
				(width 0.1)
				(type default)
			)
			(layer "F.Fab")
		)
		(fp_poly
			(pts
				(xy -2.63779 -1.249934) (xy -3.40741 -0.865378) (xy -3.40741 -1.634744)
			)
			(stroke
				(width 0)
				(type default)
			)
			(fill yes)
			(layer "F.Fab")
		)
		(fp_text user "6"
			(at -3.00355 1.5494 270)
			(unlocked yes)
			(layer "F.SilkS")
			(effects
				(font
					(size 0.635 0.4064)
					(thickness 0.1524)
				)
			)
		)
		(fp_text user "24"
			(at -2.1971 -2.51841 0)
			(unlocked yes)
			(layer "F.SilkS")
			(effects
				(font
					(size 0.635 0.4064)
					(thickness 0.1524)
				)
			)
		)
		(fp_text user "7"
			(at -1.27 3.10515 0)
			(unlocked yes)
			(layer "F.SilkS")
			(effects
				(font
					(size 0.635 0.4064)
					(thickness 0.1524)
				)
			)
		)
		(fp_text user "12"
			(at 1.5748 3.02895 0)
			(unlocked yes)
			(layer "F.SilkS")
			(effects
				(font
					(size 0.635 0.4064)
					(thickness 0.1524)
				)
			)
		)
		(fp_text user "19"
			(at 1.778 -2.95275 0)
			(unlocked yes)
			(layer "F.SilkS")
			(effects
				(font
					(size 0.635 0.4064)
					(thickness 0.1524)
				)
			)
		)
		(fp_text user "18"
			(at 2.89941 -1.95326 270)
			(unlocked yes)
			(layer "F.SilkS")
			(effects
				(font
					(size 0.635 0.4064)
					(thickness 0.1524)
				)
			)
		)
		(fp_text user "13"
			(at 3.01625 1.524 270)
			(unlocked yes)
			(layer "F.SilkS")
			(effects
				(font
					(size 0.635 0.4064)
					(thickness 0.1524)
				)
			)
		)
		(fp_text user "6"
			(at -3.00355 1.5494 270)
			(unlocked yes)
			(layer "F.Fab")
			(effects
				(font
					(size 0.635 0.4064)
					(thickness 0.1524)
				)
			)
		)
		(fp_text user "24"
			(at -1.6256 -3.01625 0)
			(unlocked yes)
			(layer "F.Fab")
			(effects
				(font
					(size 0.635 0.4064)
					(thickness 0.1524)
				)
			)
		)
		(fp_text user "7"
			(at -1.27 3.10515 0)
			(unlocked yes)
			(layer "F.Fab")
			(effects
				(font
					(size 0.635 0.4064)
					(thickness 0.1524)
				)
			)
		)
		(fp_text user "12"
			(at 1.5748 3.02895 0)
			(unlocked yes)
			(layer "F.Fab")
			(effects
				(font
					(size 0.635 0.4064)
					(thickness 0.1524)
				)
			)
		)
		(fp_text user "19"
			(at 1.7018 -3.09245 0)
			(unlocked yes)
			(layer "F.Fab")
			(effects
				(font
					(size 0.635 0.4064)
					(thickness 0.1524)
				)
			)
		)
		(fp_text user "13"
			(at 3.01625 1.524 270)
			(unlocked yes)
			(layer "F.Fab")
			(effects
				(font
					(size 0.635 0.4064)
					(thickness 0.1524)
				)
			)
		)
		(fp_text user "18"
			(at 3.04165 -1.6256 270)
			(unlocked yes)
			(layer "F.Fab")
			(effects
				(font
					(size 0.635 0.4064)
					(thickness 0.1524)
				)
			)
		)
		(pad "1" smd rect
			(at -2.050034 -1.249934 270)
			(size 0.2794 0.9144)
			(layers "F.Cu" "F.Mask" "F.Paste")
			(net "FAN_0_PWM_R2")
		)
		(pad "2" smd rect
			(at -2.050034 -0.750062 270)
			(size 0.2794 0.9144)
			(layers "F.Cu" "F.Mask" "F.Paste")
			(net "FAN_0_TACH_IL_R2")
		)
		(pad "3" smd rect
			(at -2.050034 -0.249936 270)
			(size 0.2794 0.9144)
			(layers "F.Cu" "F.Mask" "F.Paste")
			(net "FAN_1_TACH_IL_R2")
		)
		(pad "4" smd rect
			(at -2.050034 0.249936 270)
			(size 0.2794 0.9144)
			(layers "F.Cu" "F.Mask" "F.Paste")
			(net "FAN_0_TACH_OL_R2")
		)
		(pad "5" smd rect
			(at -2.050034 0.750062 270)
			(size 0.2794 0.9144)
			(layers "F.Cu" "F.Mask" "F.Paste")
			(net "FAN_1_PWM_R2")
		)
		(pad "6" smd rect
			(at -2.050034 1.249934 270)
			(size 0.2794 0.9144)
			(layers "F.Cu" "F.Mask" "F.Paste")
			(net "FAN_1_TACH_OL_R2")
		)
		(pad "7" smd rect
			(at -1.249934 2.050034)
			(size 0.2794 0.9144)
			(layers "F.Cu" "F.Mask" "F.Paste")
			(net "FAN_2_PWM_R2")
		)
		(pad "8" smd rect
			(at -0.750062 2.050034)
			(size 0.2794 0.9144)
			(layers "F.Cu" "F.Mask" "F.Paste")
			(net "FAN_2_TACH_IL_R2")
		)
		(pad "9" smd rect
			(at -0.249936 2.050034)
			(size 0.2794 0.9144)
			(layers "F.Cu" "F.Mask" "F.Paste")
			(net "GND")
		)
		(pad "10" smd rect
			(at 0.249936 2.050034)
			(size 0.2794 0.9144)
			(layers "F.Cu" "F.Mask" "F.Paste")
			(net "FAN_3_TACH_IL_R2")
		)
		(pad "11" smd rect
			(at 0.750062 2.050034)
			(size 0.2794 0.9144)
			(layers "F.Cu" "F.Mask" "F.Paste")
			(net "FAN_2_TACH_OL_R2")
		)
		(pad "12" smd rect
			(at 1.249934 2.050034)
			(size 0.2794 0.9144)
			(layers "F.Cu" "F.Mask" "F.Paste")
			(net "FAN_3_PWM_R2")
		)
		(pad "13" smd rect
			(at 2.050034 1.249934 270)
			(size 0.2794 0.9144)
			(layers "F.Cu" "F.Mask" "F.Paste")
			(net "FAN_3_TACH_OL_R2")
		)
		(pad "14" smd rect
			(at 2.050034 0.750062 270)
			(size 0.2794 0.9144)
			(layers "F.Cu" "F.Mask" "F.Paste")
			(net "NC_U403_P14")
		)
		(pad "15" smd rect
			(at 2.050034 0.249936 270)
			(size 0.2794 0.9144)
			(layers "F.Cu" "F.Mask" "F.Paste")
			(net "NC_U403_P15")
		)
		(pad "16" smd rect
			(at 2.050034 -0.249936 270)
			(size 0.2794 0.9144)
			(layers "F.Cu" "F.Mask" "F.Paste")
			(net "NC_U403_P16")
		)
		(pad "17" smd rect
			(at 2.050034 -0.750062 270)
			(size 0.2794 0.9144)
			(layers "F.Cu" "F.Mask" "F.Paste")
			(net "NC_U403_P17")
		)
		(pad "18" smd rect
			(at 2.050034 -1.249934 270)
			(size 0.2794 0.9144)
			(layers "F.Cu" "F.Mask" "F.Paste")
			(net "U403_ADD0")
		)
		(pad "19" smd rect
			(at 1.249934 -2.050034)
			(size 0.2794 0.9144)
			(layers "F.Cu" "F.Mask" "F.Paste")
			(net "SMB_PDBV_FAN_R_U403_SCL")
		)
		(pad "20" smd rect
			(at 0.750062 -2.050034)
			(size 0.2794 0.9144)
			(layers "F.Cu" "F.Mask" "F.Paste")
			(net "SMB_PDBV_FAN_R_U403_SDA")
		)
		(pad "21" smd rect
			(at 0.249936 -2.050034)
			(size 0.2794 0.9144)
			(layers "F.Cu" "F.Mask" "F.Paste")
			(net "P3V3_AUX")
		)
		(pad "22" smd rect
			(at -0.249936 -2.050034)
			(size 0.2794 0.9144)
			(layers "F.Cu" "F.Mask" "F.Paste")
			(net "NC_U403_P22")
		)
		(pad "23" smd rect
			(at -0.750062 -2.050034)
			(size 0.2794 0.9144)
			(layers "F.Cu" "F.Mask" "F.Paste")
			(net "U403_ADD1")
		)
		(pad "24" smd rect
			(at -1.249934 -2.050034)
			(size 0.2794 0.9144)
			(layers "F.Cu" "F.Mask" "F.Paste")
			(net "U403_ADD2")
		)
		(pad "TH" smd rect
			(at 0 0)
			(size 2.7686 2.7686)
			(layers "F.Cu" "F.Mask" "F.Paste")
			(net "GND")
		)
		(zone
			(layer "F.Cu")
			(hatch none 0.5)
			(connect_pads
				(clearance 0)
			)
			(min_thickness 0.25)
			(keepout
				(tracks not_allowed)
				(vias allowed)
				(pads allowed)
				(copperpour not_allowed)
				(footprints allowed)
			)
			(placement
				(enabled no)
				(sheetname "")
			)
			(fill
				(thermal_gap 0.5)
				(thermal_bridge_width 0.5)
				(island_removal_mode 0)
			)
			(polygon
				(pts
					(xy 42.418 -130.048) (xy 42.418 -133.096) (xy 45.466 -133.096) (xy 45.466 -133.0198) (xy 42.4942 -133.0198)
					(xy 42.4942 -130.1242) (xy 45.3898 -130.1242) (xy 45.3898 -132.9944) (xy 45.466 -132.9944) (xy 45.466 -130.048)
				)
			)
		)
	)
	(footprint ""
		(layer "F.Cu")
		(at 33.02 -116.008912 180)
		(property "Reference" "C2042"
			(at 0 0 180)
			(layer "F.SilkS")
			(hide yes)
			(effects
				(font
					(size 1.27 1.27)
				)
			)
		)
		(property "Value" ""
			(at 0 0 180)
			(layer "F.Fab")
			(effects
				(font
					(size 1.27 1.27)
				)
			)
		)
		(duplicate_pad_numbers_are_jumpers no)
		(fp_line
			(start 0.7874 0.4064)
			(end -0.7874 0.4064)
			(stroke
				(width 0.1524)
				(type default)
			)
			(layer "F.SilkS")
		)
		(fp_line
			(start 0.7874 -0.4064)
			(end 0.7874 0.4064)
			(stroke
				(width 0.1524)
				(type default)
			)
			(layer "F.SilkS")
		)
		(fp_line
			(start -0.7874 0.4064)
			(end -0.7874 -0.4064)
			(stroke
				(width 0.1524)
				(type default)
			)
			(layer "F.SilkS")
		)
		(fp_line
			(start -0.7874 -0.4064)
			(end 0.7874 -0.4064)
			(stroke
				(width 0.1524)
				(type default)
			)
			(layer "F.SilkS")
		)
		(fp_line
			(start 0.67945 0.3048)
			(end 0.120396 0.3048)
			(stroke
				(width 0.1)
				(type default)
			)
			(layer "F.Fab")
		)
		(fp_line
			(start 0.67945 -0.3048)
			(end 0.67945 0.3048)
			(stroke
				(width 0.1)
				(type default)
			)
			(layer "F.Fab")
		)
		(fp_line
			(start 0.12065 -0.2794)
			(end 0.12065 -0.3048)
			(stroke
				(width 0.1)
				(type default)
			)
			(layer "F.Fab")
		)
		(fp_line
			(start 0.12065 -0.3048)
			(end 0.67945 -0.3048)
			(stroke
				(width 0.1)
				(type default)
			)
			(layer "F.Fab")
		)
		(fp_line
			(start 0.120396 0.3048)
			(end 0.120396 0.2794)
			(stroke
				(width 0.1)
				(type default)
			)
			(layer "F.Fab")
		)
		(fp_line
			(start 0.120396 0.2794)
			(end -0.12065 0.2794)
			(stroke
				(width 0.1)
				(type default)
			)
			(layer "F.Fab")
		)
		(fp_line
			(start -0.12065 0.3048)
			(end -0.67945 0.3048)
			(stroke
				(width 0.1)
				(type default)
			)
			(layer "F.Fab")
		)
		(fp_line
			(start -0.12065 0.2794)
			(end -0.12065 0.3048)
			(stroke
				(width 0.1)
				(type default)
			)
			(layer "F.Fab")
		)
		(fp_line
			(start -0.12065 -0.2794)
			(end 0.12065 -0.2794)
			(stroke
				(width 0.1)
				(type default)
			)
			(layer "F.Fab")
		)
		(fp_line
			(start -0.12065 -0.305054)
			(end -0.12065 -0.2794)
			(stroke
				(width 0.1)
				(type default)
			)
			(layer "F.Fab")
		)
		(fp_line
			(start -0.67945 0.3048)
			(end -0.67945 -0.305054)
			(stroke
				(width 0.1)
				(type default)
			)
			(layer "F.Fab")
		)
		(fp_line
			(start -0.67945 -0.305054)
			(end -0.12065 -0.305054)
			(stroke
				(width 0.1)
				(type default)
			)
			(layer "F.Fab")
		)
		(pad "1" smd circle
			(at -0.40005 0 180)
			(size 0 0)
			(layers "F.Cu" "F.Mask" "F.Paste")
			(net "FAN_2_TACH_IL_R")
		)
		(pad "2" smd circle
			(at 0.40005 0 180)
			(size 0 0)
			(layers "F.Cu" "F.Mask" "F.Paste")
			(net "GND")
		)
	)
	(footprint ""
		(layer "F.Cu")
		(at 37.846 -130.048 180)
		(property "Reference" "R5603"
			(at 0 0 180)
			(layer "F.SilkS")
			(hide yes)
			(effects
				(font
					(size 1.27 1.27)
				)
			)
		)
		(property "Value" ""
			(at 0 0 180)
			(layer "F.Fab")
			(effects
				(font
					(size 1.27 1.27)
				)
			)
		)
		(duplicate_pad_numbers_are_jumpers no)
		(fp_line
			(start 0.7874 0.4064)
			(end -0.7874 0.4064)
			(stroke
				(width 0.1524)
				(type default)
			)
			(layer "F.SilkS")
		)
		(fp_line
			(start 0.7874 -0.4064)
			(end 0.7874 0.4064)
			(stroke
				(width 0.1524)
				(type default)
			)
			(layer "F.SilkS")
		)
		(fp_line
			(start -0.7874 0.4064)
			(end -0.7874 -0.4064)
			(stroke
				(width 0.1524)
				(type default)
			)
			(layer "F.SilkS")
		)
		(fp_line
			(start -0.7874 -0.4064)
			(end 0.7874 -0.4064)
			(stroke
				(width 0.1524)
				(type default)
			)
			(layer "F.SilkS")
		)
		(fp_line
			(start 0.67945 0.3048)
			(end 0.120396 0.3048)
			(stroke
				(width 0.1)
				(type default)
			)
			(layer "F.Fab")
		)
		(fp_line
			(start 0.67945 -0.3048)
			(end 0.67945 0.3048)
			(stroke
				(width 0.1)
				(type default)
			)
			(layer "F.Fab")
		)
		(fp_line
			(start 0.12065 -0.2794)
			(end 0.12065 -0.3048)
			(stroke
				(width 0.1)
				(type default)
			)
			(layer "F.Fab")
		)
		(fp_line
			(start 0.12065 -0.3048)
			(end 0.67945 -0.3048)
			(stroke
				(width 0.1)
				(type default)
			)
			(layer "F.Fab")
		)
		(fp_line
			(start 0.120396 0.3048)
			(end 0.120396 0.2794)
			(stroke
				(width 0.1)
				(type default)
			)
			(layer "F.Fab")
		)
		(fp_line
			(start 0.120396 0.2794)
			(end -0.12065 0.2794)
			(stroke
				(width 0.1)
				(type default)
			)
			(layer "F.Fab")
		)
		(fp_line
			(start -0.12065 0.3048)
			(end -0.67945 0.3048)
			(stroke
				(width 0.1)
				(type default)
			)
			(layer "F.Fab")
		)
		(fp_line
			(start -0.12065 0.2794)
			(end -0.12065 0.3048)
			(stroke
				(width 0.1)
				(type default)
			)
			(layer "F.Fab")
		)
		(fp_line
			(start -0.12065 -0.2794)
			(end 0.12065 -0.2794)
			(stroke
				(width 0.1)
				(type default)
			)
			(layer "F.Fab")
		)
		(fp_line
			(start -0.12065 -0.305054)
			(end -0.12065 -0.2794)
			(stroke
				(width 0.1)
				(type default)
			)
			(layer "F.Fab")
		)
		(fp_line
			(start -0.67945 0.3048)
			(end -0.67945 -0.305054)
			(stroke
				(width 0.1)
				(type default)
			)
			(layer "F.Fab")
		)
		(fp_line
			(start -0.67945 -0.305054)
			(end -0.12065 -0.305054)
			(stroke
				(width 0.1)
				(type default)
			)
			(layer "F.Fab")
		)
		(pad "1" smd rect
			(at -0.40005 0)
			(size 0.4572 0.508)
			(layers "F.Cu" "F.Mask" "F.Paste")
			(net "FAN_2_PWM")
		)
		(pad "2" smd rect
			(at 0.40005 0)
			(size 0.4572 0.508)
			(layers "F.Cu" "F.Mask" "F.Paste")
			(net "FAN_2_PWM_R1")
		)
	)
	(footprint ""
		(layer "F.Cu")
		(at 20.828 -176.784)
		(property "Reference" "R5686"
			(at 0 0 0)
			(layer "F.SilkS")
			(hide yes)
			(effects
				(font
					(size 1.27 1.27)
				)
			)
		)
		(property "Value" ""
			(at 0 0 0)
			(layer "F.Fab")
			(effects
				(font
					(size 1.27 1.27)
				)
			)
		)
		(duplicate_pad_numbers_are_jumpers no)
		(fp_line
			(start -0.7874 -0.4064)
			(end 0.7874 -0.4064)
			(stroke
				(width 0.1524)
				(type default)
			)
			(layer "F.SilkS")
		)
		(fp_line
			(start -0.7874 0.4064)
			(end -0.7874 -0.4064)
			(stroke
				(width 0.1524)
				(type default)
			)
			(layer "F.SilkS")
		)
		(fp_line
			(start 0.7874 -0.4064)
			(end 0.7874 0.4064)
			(stroke
				(width 0.1524)
				(type default)
			)
			(layer "F.SilkS")
		)
		(fp_line
			(start 0.7874 0.4064)
			(end -0.7874 0.4064)
			(stroke
				(width 0.1524)
				(type default)
			)
			(layer "F.SilkS")
		)
		(fp_line
			(start -0.67945 -0.305054)
			(end -0.12065 -0.305054)
			(stroke
				(width 0.1)
				(type default)
			)
			(layer "F.Fab")
		)
		(fp_line
			(start -0.67945 0.3048)
			(end -0.67945 -0.305054)
			(stroke
				(width 0.1)
				(type default)
			)
			(layer "F.Fab")
		)
		(fp_line
			(start -0.12065 -0.305054)
			(end -0.12065 -0.2794)
			(stroke
				(width 0.1)
				(type default)
			)
			(layer "F.Fab")
		)
		(fp_line
			(start -0.12065 -0.2794)
			(end 0.12065 -0.2794)
			(stroke
				(width 0.1)
				(type default)
			)
			(layer "F.Fab")
		)
		(fp_line
			(start -0.12065 0.2794)
			(end -0.12065 0.3048)
			(stroke
				(width 0.1)
				(type default)
			)
			(layer "F.Fab")
		)
		(fp_line
			(start -0.12065 0.3048)
			(end -0.67945 0.3048)
			(stroke
				(width 0.1)
				(type default)
			)
			(layer "F.Fab")
		)
		(fp_line
			(start 0.120396 0.2794)
			(end -0.12065 0.2794)
			(stroke
				(width 0.1)
				(type default)
			)
			(layer "F.Fab")
		)
		(fp_line
			(start 0.120396 0.3048)
			(end 0.120396 0.2794)
			(stroke
				(width 0.1)
				(type default)
			)
			(layer "F.Fab")
		)
		(fp_line
			(start 0.12065 -0.3048)
			(end 0.67945 -0.3048)
			(stroke
				(width 0.1)
				(type default)
			)
			(layer "F.Fab")
		)
		(fp_line
			(start 0.12065 -0.2794)
			(end 0.12065 -0.3048)
			(stroke
				(width 0.1)
				(type default)
			)
			(layer "F.Fab")
		)
		(fp_line
			(start 0.67945 -0.3048)
			(end 0.67945 0.3048)
			(stroke
				(width 0.1)
				(type default)
			)
			(layer "F.Fab")
		)
		(fp_line
			(start 0.67945 0.3048)
			(end 0.120396 0.3048)
			(stroke
				(width 0.1)
				(type default)
			)
			(layer "F.Fab")
		)
		(pad "1" smd circle
			(at -0.40005 0)
			(size 0 0)
			(layers "F.Cu" "F.Mask" "F.Paste")
			(net "FM_BOARD_ID0")
		)
		(pad "2" smd circle
			(at 0.40005 0)
			(size 0 0)
			(layers "F.Cu" "F.Mask" "F.Paste")
			(net "GND")
		)
	)
)
